# T6G (Grand Teton) — schematic netlist excerpt (pin names and nets, part order shuffled) for the footprints in the layout excerpt that follows; sources: Cadence DE-HDL packaged netlist, KiCad conversion of 04192023_DAF0TMB3IC0_F0TG_MB_C_brd_V02_OCP.brd

R1297  Q_RES  0 5% CHIP  pkg 0402LF  page 159 : A = I3C_SPD_DDRAF_CPU0_SCL ; B = I3C_SPD_DDRAF_CPU0_LVC1_SCL
R1354  Q_RES  0 5% CHIP  pkg 0402LF  page 172 : A = HDT_HDR_R_TDI ; B = HDT_HDR_TDI
TP19  TP  NA  pkg TP  page 54 : TP = VSENSE_PVDD18_S5_P1_DP

(kicad_pcb
	(version 20260206)
	(generator "pcbnew")
	(generator_version "10.0")
	(general
		(thickness 1.6)
		(legacy_teardrops no)
	)
	(paper "A4")
	(title_block
		(title "04192023_DAF0TMB3IC0_F0TG_MB_C_brd_V02_OCP.brd")
		(comment 1 "Grand Teton / footprints 2487-2489 of 8354")
	)
	(layers
		(0 "F.Cu" signal "TOP")
		(4 "In1.Cu" signal "GND")
		(6 "In2.Cu" signal "IN1")
		(8 "In3.Cu" signal "GND1")
		(10 "In4.Cu" signal "IN2")
		(12 "In5.Cu" signal "GND2")
		(14 "In6.Cu" signal "IN3")
		(16 "In7.Cu" signal "GND3")
		(18 "In8.Cu" signal "VCC")
		(20 "In9.Cu" signal "VCC1")
		(22 "In10.Cu" signal "GND4")
		(24 "In11.Cu" signal "IN4")
		(26 "In12.Cu" signal "GND5")
		(28 "In13.Cu" signal "IN5")
		(30 "In14.Cu" signal "GND6")
		(32 "In15.Cu" signal "IN6")
		(34 "In16.Cu" signal "GND7")
		(2 "B.Cu" signal "BOTTOM")
		(9 "F.Adhes" user "F.Adhesive")
		(11 "B.Adhes" user "B.Adhesive")
		(13 "F.Paste" user "Package Geometry/Pastemask Top")
		(15 "B.Paste" user "Package Geometry/Pastemask Bottom")
		(5 "F.SilkS" user "Ref Des/Silkscreen Top")
		(7 "B.SilkS" user "Ref Des/Silkscreen Bottom")
		(1 "F.Mask" user "Board Geometry/Soldermask Top")
		(3 "B.Mask" user "Board Geometry/Soldermask Bottom")
		(17 "Dwgs.User" user "User.Drawings")
		(19 "Cmts.User" user "User.Comments")
		(21 "Eco1.User" user "User.Eco1")
		(23 "Eco2.User" user "User.Eco2")
		(25 "Edge.Cuts" user "Board Geometry/Outline")
		(27 "Margin" user)
		(31 "F.CrtYd" user "Package Geometry/Place Bound Top")
		(29 "B.CrtYd" user "Package Geometry/Place Bound Bottom")
		(35 "F.Fab" user "Ref Des/Assembly Top")
		(33 "B.Fab" user "Ref Des/Assembly Bottom")
	)
	(footprint ""
		(layer "F.Cu")
		(at 61.88075 -193.594228)
		(property "Reference" "TP19"
			(at 0 0 0)
			(layer "F.SilkS")
			(hide yes)
			(effects
				(font
					(size 1.27 1.27)
				)
			)
		)
		(property "Value" ""
			(at 0 0 0)
			(layer "F.Fab")
			(effects
				(font
					(size 1.27 1.27)
				)
			)
		)
		(duplicate_pad_numbers_are_jumpers no)
		(pad "1" smd circle
			(at 0 0)
			(size 0.762 0.762)
			(layers "F.Cu" "F.Mask" "F.Paste")
			(net "VSENSE_PVDD18_S5_P1_DP")
		)
	)
	(footprint ""
		(layer "F.Cu")
		(at 296.515028 -146.202908 180)
		(property "Reference" "R1297"
			(at 0 0 180)
			(layer "F.SilkS")
			(hide yes)
			(effects
				(font
					(size 1.27 1.27)
				)
			)
		)
		(property "Value" ""
			(at 0 0 180)
			(layer "F.Fab")
			(effects
				(font
					(size 1.27 1.27)
				)
			)
		)
		(duplicate_pad_numbers_are_jumpers no)
		(fp_line
			(start 0.7874 0.4064)
			(end -0.7874 0.4064)
			(stroke
				(width 0.1524)
				(type default)
			)
			(layer "F.SilkS")
		)
		(fp_line
			(start 0.7874 -0.4064)
			(end 0.7874 0.4064)
			(stroke
				(width 0.1524)
				(type default)
			)
			(layer "F.SilkS")
		)
		(fp_line
			(start -0.7874 0.4064)
			(end -0.7874 -0.4064)
			(stroke
				(width 0.1524)
				(type default)
			)
			(layer "F.SilkS")
		)
		(fp_line
			(start -0.7874 -0.4064)
			(end 0.7874 -0.4064)
			(stroke
				(width 0.1524)
				(type default)
			)
			(layer "F.SilkS")
		)
		(fp_line
			(start 0.67945 0.3048)
			(end 0.120396 0.3048)
			(stroke
				(width 0.1)
				(type default)
			)
			(layer "F.Fab")
		)
		(fp_line
			(start 0.67945 -0.3048)
			(end 0.67945 0.3048)
			(stroke
				(width 0.1)
				(type default)
			)
			(layer "F.Fab")
		)
		(fp_line
			(start 0.12065 -0.2794)
			(end 0.12065 -0.3048)
			(stroke
				(width 0.1)
				(type default)
			)
			(layer "F.Fab")
		)
		(fp_line
			(start 0.12065 -0.3048)
			(end 0.67945 -0.3048)
			(stroke
				(width 0.1)
				(type default)
			)
			(layer "F.Fab")
		)
		(fp_line
			(start 0.120396 0.3048)
			(end 0.120396 0.2794)
			(stroke
				(width 0.1)
				(type default)
			)
			(layer "F.Fab")
		)
		(fp_line
			(start 0.120396 0.2794)
			(end -0.12065 0.2794)
			(stroke
				(width 0.1)
				(type default)
			)
			(layer "F.Fab")
		)
		(fp_line
			(start -0.12065 0.3048)
			(end -0.67945 0.3048)
			(stroke
				(width 0.1)
				(type default)
			)
			(layer "F.Fab")
		)
		(fp_line
			(start -0.12065 0.2794)
			(end -0.12065 0.3048)
			(stroke
				(width 0.1)
				(type default)
			)
			(layer "F.Fab")
		)
		(fp_line
			(start -0.12065 -0.2794)
			(end 0.12065 -0.2794)
			(stroke
				(width 0.1)
				(type default)
			)
			(layer "F.Fab")
		)
		(fp_line
			(start -0.12065 -0.305054)
			(end -0.12065 -0.2794)
			(stroke
				(width 0.1)
				(type default)
			)
			(layer "F.Fab")
		)
		(fp_line
			(start -0.67945 0.3048)
			(end -0.67945 -0.305054)
			(stroke
				(width 0.1)
				(type default)
			)
			(layer "F.Fab")
		)
		(fp_line
			(start -0.67945 -0.305054)
			(end -0.12065 -0.305054)
			(stroke
				(width 0.1)
				(type default)
			)
			(layer "F.Fab")
		)
		(pad "1" smd rect
			(at -0.40005 0)
			(size 0.4572 0.508)
			(layers "F.Cu" "F.Mask" "F.Paste")
			(net "I3C_SPD_DDRAF_CPU0_SCL")
		)
		(pad "2" smd rect
			(at 0.40005 0)
			(size 0.4572 0.508)
			(layers "F.Cu" "F.Mask" "F.Paste")
			(net "I3C_SPD_DDRAF_CPU0_LVC1_SCL")
		)
	)
	(footprint ""
		(layer "F.Cu")
		(at 386.211826 -56.1975 180)
		(property "Reference" "R1354"
			(at 0 0 180)
			(layer "F.SilkS")
			(hide yes)
			(effects
				(font
					(size 1.27 1.27)
				)
			)
		)
		(property "Value" ""
			(at 0 0 180)
			(layer "F.Fab")
			(effects
				(font
					(size 1.27 1.27)
				)
			)
		)
		(duplicate_pad_numbers_are_jumpers no)
		(fp_line
			(start 0.7874 0.4064)
			(end -0.7874 0.4064)
			(stroke
				(width 0.1524)
				(type default)
			)
			(layer "F.SilkS")
		)
		(fp_line
			(start 0.7874 -0.4064)
			(end 0.7874 0.4064)
			(stroke
				(width 0.1524)
				(type default)
			)
			(layer "F.SilkS")
		)
		(fp_line
			(start -0.7874 0.4064)
			(end -0.7874 -0.4064)
			(stroke
				(width 0.1524)
				(type default)
			)
			(layer "F.SilkS")
		)
		(fp_line
			(start -0.7874 -0.4064)
			(end 0.7874 -0.4064)
			(stroke
				(width 0.1524)
				(type default)
			)
			(layer "F.SilkS")
		)
		(fp_line
			(start 0.67945 0.3048)
			(end 0.120396 0.3048)
			(stroke
				(width 0.1)
				(type default)
			)
			(layer "F.Fab")
		)
		(fp_line
			(start 0.67945 -0.3048)
			(end 0.67945 0.3048)
			(stroke
				(width 0.1)
				(type default)
			)
			(layer "F.Fab")
		)
		(fp_line
			(start 0.12065 -0.2794)
			(end 0.12065 -0.3048)
			(stroke
				(width 0.1)
				(type default)
			)
			(layer "F.Fab")
		)
		(fp_line
			(start 0.12065 -0.3048)
			(end 0.67945 -0.3048)
			(stroke
				(width 0.1)
				(type default)
			)
			(layer "F.Fab")
		)
		(fp_line
			(start 0.120396 0.3048)
			(end 0.120396 0.2794)
			(stroke
				(width 0.1)
				(type default)
			)
			(layer "F.Fab")
		)
		(fp_line
			(start 0.120396 0.2794)
			(end -0.12065 0.2794)
			(stroke
				(width 0.1)
				(type default)
			)
			(layer "F.Fab")
		)
		(fp_line
			(start -0.12065 0.3048)
			(end -0.67945 0.3048)
			(stroke
				(width 0.1)
				(type default)
			)
			(layer "F.Fab")
		)
		(fp_line
			(start -0.12065 0.2794)
			(end -0.12065 0.3048)
			(stroke
				(width 0.1)
				(type default)
			)
			(layer "F.Fab")
		)
		(fp_line
			(start -0.12065 -0.2794)
			(end 0.12065 -0.2794)
			(stroke
				(width 0.1)
				(type default)
			)
			(layer "F.Fab")
		)
		(fp_line
			(start -0.12065 -0.305054)
			(end -0.12065 -0.2794)
			(stroke
				(width 0.1)
				(type default)
			)
			(layer "F.Fab")
		)
		(fp_line
			(start -0.67945 0.3048)
			(end -0.67945 -0.305054)
			(stroke
				(width 0.1)
				(type default)
			)
			(layer "F.Fab")
		)
		(fp_line
			(start -0.67945 -0.305054)
			(end -0.12065 -0.305054)
			(stroke
				(width 0.1)
				(type default)
			)
			(layer "F.Fab")
		)
		(pad "1" smd circle
			(at -0.40005 0 180)
			(size 0 0)
			(layers "F.Cu" "F.Mask" "F.Paste")
			(net "HDT_HDR_R_TDI")
		)
		(pad "2" smd circle
			(at 0.40005 0 180)
			(size 0 0)
			(layers "F.Cu" "F.Mask" "F.Paste")
			(net "HDT_HDR_TDI")
		)
	)
)
